(kicad_pcb
	(version 20260206)
	(generator "pcbnew")
	(generator_version "10.0")
	(general
		(thickness 1.6)
		(legacy_teardrops no)
	)
	(paper "A4")
	(title_block
		(title "01162023_DA0F0TEBIF0_F0T_Expander_BD_F_brd_V02_OCP.brd")
		(comment 1 "Grand Teton / footprints 5685-5691 of 9728")
	)
	(layers
		(0 "F.Cu" signal "TOP")
		(4 "In1.Cu" signal "GND")
		(6 "In2.Cu" signal "VCC")
		(8 "In3.Cu" signal "VCC1")
		(10 "In4.Cu" signal "GND1")
		(12 "In5.Cu" signal "IN1")
		(14 "In6.Cu" signal "GND2")
		(16 "In7.Cu" signal "IN2")
		(18 "In8.Cu" signal "GND3")
		(20 "In9.Cu" signal "IN3")
		(22 "In10.Cu" signal "GND4")
		(24 "In11.Cu" signal "IN4")
		(26 "In12.Cu" signal "GND5")
		(28 "In13.Cu" signal "IN5")
		(30 "In14.Cu" signal "GND6")
		(32 "In15.Cu" signal "IN6")
		(34 "In16.Cu" signal "GND7")
		(2 "B.Cu" signal "BOTTOM")
		(9 "F.Adhes" user "F.Adhesive")
		(11 "B.Adhes" user "B.Adhesive")
		(13 "F.Paste" user "Package Geometry/Pastemask Top")
		(15 "B.Paste" user "Package Geometry/Pastemask Bottom")
		(5 "F.SilkS" user "Ref Des/Silkscreen Top")
		(7 "B.SilkS" user "Ref Des/Silkscreen Bottom")
		(1 "F.Mask" user "Board Geometry/Soldermask Top")
		(3 "B.Mask" user "Board Geometry/Soldermask Bottom")
		(17 "Dwgs.User" user "User.Drawings")
		(19 "Cmts.User" user "User.Comments")
		(21 "Eco1.User" user "User.Eco1")
		(23 "Eco2.User" user "User.Eco2")
		(25 "Edge.Cuts" user "Board Geometry/Outline")
		(27 "Margin" user)
		(31 "F.CrtYd" user "Package Geometry/Place Bound Top")
		(29 "B.CrtYd" user "Package Geometry/Place Bound Bottom")
		(35 "F.Fab" user "Ref Des/Assembly Top")
		(33 "B.Fab" user "Ref Des/Assembly Bottom")
	)
	(footprint ""
		(layer "F.Cu")
		(at 190.226696 -409.795472 -90)
		(property "Reference" "R4419"
			(at 0 0 270)
			(layer "F.SilkS")
			(hide yes)
			(effects
				(font
					(size 1.27 1.27)
				)
			)
		)
		(property "Value" ""
			(at 0 0 270)
			(layer "F.Fab")
			(effects
				(font
					(size 1.27 1.27)
				)
			)
		)
		(duplicate_pad_numbers_are_jumpers no)
		(fp_line
			(start -0.7874 0.4064)
			(end -0.7874 -0.4064)
			(stroke
				(width 0.1524)
				(type default)
			)
			(layer "F.SilkS")
		)
		(fp_line
			(start 0.7874 0.4064)
			(end -0.7874 0.4064)
			(stroke
				(width 0.1524)
				(type default)
			)
			(layer "F.SilkS")
		)
		(fp_line
			(start -0.7874 -0.4064)
			(end 0.7874 -0.4064)
			(stroke
				(width 0.1524)
				(type default)
			)
			(layer "F.SilkS")
		)
		(fp_line
			(start 0.7874 -0.4064)
			(end 0.7874 0.4064)
			(stroke
				(width 0.1524)
				(type default)
			)
			(layer "F.SilkS")
		)
		(fp_line
			(start -0.67945 0.3048)
			(end -0.67945 -0.305054)
			(stroke
				(width 0.1)
				(type default)
			)
			(layer "F.Fab")
		)
		(fp_line
			(start -0.12065 0.3048)
			(end -0.67945 0.3048)
			(stroke
				(width 0.1)
				(type default)
			)
			(layer "F.Fab")
		)
		(fp_line
			(start 0.120396 0.3048)
			(end 0.120396 0.2794)
			(stroke
				(width 0.1)
				(type default)
			)
			(layer "F.Fab")
		)
		(fp_line
			(start 0.67945 0.3048)
			(end 0.120396 0.3048)
			(stroke
				(width 0.1)
				(type default)
			)
			(layer "F.Fab")
		)
		(fp_line
			(start -0.12065 0.2794)
			(end -0.12065 0.3048)
			(stroke
				(width 0.1)
				(type default)
			)
			(layer "F.Fab")
		)
		(fp_line
			(start 0.120396 0.2794)
			(end -0.12065 0.2794)
			(stroke
				(width 0.1)
				(type default)
			)
			(layer "F.Fab")
		)
		(fp_line
			(start -0.12065 -0.2794)
			(end 0.12065 -0.2794)
			(stroke
				(width 0.1)
				(type default)
			)
			(layer "F.Fab")
		)
		(fp_line
			(start 0.12065 -0.2794)
			(end 0.12065 -0.3048)
			(stroke
				(width 0.1)
				(type default)
			)
			(layer "F.Fab")
		)
		(fp_line
			(start 0.12065 -0.3048)
			(end 0.67945 -0.3048)
			(stroke
				(width 0.1)
				(type default)
			)
			(layer "F.Fab")
		)
		(fp_line
			(start 0.67945 -0.3048)
			(end 0.67945 0.3048)
			(stroke
				(width 0.1)
				(type default)
			)
			(layer "F.Fab")
		)
		(fp_line
			(start -0.67945 -0.305054)
			(end -0.12065 -0.305054)
			(stroke
				(width 0.1)
				(type default)
			)
			(layer "F.Fab")
		)
		(fp_line
			(start -0.12065 -0.305054)
			(end -0.12065 -0.2794)
			(stroke
				(width 0.1)
				(type default)
			)
			(layer "F.Fab")
		)
		(pad "1" smd circle
			(at -0.40005 0 270)
			(size 0 0)
			(layers "F.Cu" "F.Mask" "F.Paste")
			(net "GND")
		)
		(pad "2" smd circle
			(at 0.40005 0 270)
			(size 0 0)
			(layers "F.Cu" "F.Mask" "F.Paste")
			(net "A_P12V_AUX_FP_TRIGGER")
		)
	)
	(footprint ""
		(layer "F.Cu")
		(at 434.420518 -26.666444 -90)
		(property "Reference" "R4083"
			(at 0 0 270)
			(layer "F.SilkS")
			(hide yes)
			(effects
				(font
					(size 1.27 1.27)
				)
			)
		)
		(property "Value" ""
			(at 0 0 270)
			(layer "F.Fab")
			(effects
				(font
					(size 1.27 1.27)
				)
			)
		)
		(duplicate_pad_numbers_are_jumpers no)
		(fp_line
			(start -0.7874 0.4064)
			(end -0.7874 -0.4064)
			(stroke
				(width 0.1524)
				(type default)
			)
			(layer "F.SilkS")
		)
		(fp_line
			(start 0.7874 0.4064)
			(end -0.7874 0.4064)
			(stroke
				(width 0.1524)
				(type default)
			)
			(layer "F.SilkS")
		)
		(fp_line
			(start -0.7874 -0.4064)
			(end 0.7874 -0.4064)
			(stroke
				(width 0.1524)
				(type default)
			)
			(layer "F.SilkS")
		)
		(fp_line
			(start 0.7874 -0.4064)
			(end 0.7874 0.4064)
			(stroke
				(width 0.1524)
				(type default)
			)
			(layer "F.SilkS")
		)
		(fp_line
			(start -0.67945 0.3048)
			(end -0.67945 -0.305054)
			(stroke
				(width 0.1)
				(type default)
			)
			(layer "F.Fab")
		)
		(fp_line
			(start -0.12065 0.3048)
			(end -0.67945 0.3048)
			(stroke
				(width 0.1)
				(type default)
			)
			(layer "F.Fab")
		)
		(fp_line
			(start 0.120396 0.3048)
			(end 0.120396 0.2794)
			(stroke
				(width 0.1)
				(type default)
			)
			(layer "F.Fab")
		)
		(fp_line
			(start 0.67945 0.3048)
			(end 0.120396 0.3048)
			(stroke
				(width 0.1)
				(type default)
			)
			(layer "F.Fab")
		)
		(fp_line
			(start -0.12065 0.2794)
			(end -0.12065 0.3048)
			(stroke
				(width 0.1)
				(type default)
			)
			(layer "F.Fab")
		)
		(fp_line
			(start 0.120396 0.2794)
			(end -0.12065 0.2794)
			(stroke
				(width 0.1)
				(type default)
			)
			(layer "F.Fab")
		)
		(fp_line
			(start -0.12065 -0.2794)
			(end 0.12065 -0.2794)
			(stroke
				(width 0.1)
				(type default)
			)
			(layer "F.Fab")
		)
		(fp_line
			(start 0.12065 -0.2794)
			(end 0.12065 -0.3048)
			(stroke
				(width 0.1)
				(type default)
			)
			(layer "F.Fab")
		)
		(fp_line
			(start 0.12065 -0.3048)
			(end 0.67945 -0.3048)
			(stroke
				(width 0.1)
				(type default)
			)
			(layer "F.Fab")
		)
		(fp_line
			(start 0.67945 -0.3048)
			(end 0.67945 0.3048)
			(stroke
				(width 0.1)
				(type default)
			)
			(layer "F.Fab")
		)
		(fp_line
			(start -0.67945 -0.305054)
			(end -0.12065 -0.305054)
			(stroke
				(width 0.1)
				(type default)
			)
			(layer "F.Fab")
		)
		(fp_line
			(start -0.12065 -0.305054)
			(end -0.12065 -0.2794)
			(stroke
				(width 0.1)
				(type default)
			)
			(layer "F.Fab")
		)
		(pad "1" smd circle
			(at -0.40005 0 270)
			(size 0 0)
			(layers "F.Cu" "F.Mask" "F.Paste")
			(net "PRSNT_SSD15_R_N")
		)
		(pad "2" smd circle
			(at 0.40005 0 270)
			(size 0 0)
			(layers "F.Cu" "F.Mask" "F.Paste")
			(net "PRSNT_SSD15_N")
		)
	)
	(footprint ""
		(layer "F.Cu")
		(at 277.742396 -414.88995 -90)
		(property "Reference" "R1814"
			(at 0 0 270)
			(layer "F.SilkS")
			(hide yes)
			(effects
				(font
					(size 1.27 1.27)
				)
			)
		)
		(property "Value" ""
			(at 0 0 270)
			(layer "F.Fab")
			(effects
				(font
					(size 1.27 1.27)
				)
			)
		)
		(duplicate_pad_numbers_are_jumpers no)
		(fp_line
			(start -0.7874 0.4064)
			(end -0.7874 -0.4064)
			(stroke
				(width 0.1524)
				(type default)
			)
			(layer "F.SilkS")
		)
		(fp_line
			(start 0.7874 0.4064)
			(end -0.7874 0.4064)
			(stroke
				(width 0.1524)
				(type default)
			)
			(layer "F.SilkS")
		)
		(fp_line
			(start -0.7874 -0.4064)
			(end 0.7874 -0.4064)
			(stroke
				(width 0.1524)
				(type default)
			)
			(layer "F.SilkS")
		)
		(fp_line
			(start 0.7874 -0.4064)
			(end 0.7874 0.4064)
			(stroke
				(width 0.1524)
				(type default)
			)
			(layer "F.SilkS")
		)
		(fp_line
			(start -0.67945 0.3048)
			(end -0.67945 -0.305054)
			(stroke
				(width 0.1)
				(type default)
			)
			(layer "F.Fab")
		)
		(fp_line
			(start -0.12065 0.3048)
			(end -0.67945 0.3048)
			(stroke
				(width 0.1)
				(type default)
			)
			(layer "F.Fab")
		)
		(fp_line
			(start 0.120396 0.3048)
			(end 0.120396 0.2794)
			(stroke
				(width 0.1)
				(type default)
			)
			(layer "F.Fab")
		)
		(fp_line
			(start 0.67945 0.3048)
			(end 0.120396 0.3048)
			(stroke
				(width 0.1)
				(type default)
			)
			(layer "F.Fab")
		)
		(fp_line
			(start -0.12065 0.2794)
			(end -0.12065 0.3048)
			(stroke
				(width 0.1)
				(type default)
			)
			(layer "F.Fab")
		)
		(fp_line
			(start 0.120396 0.2794)
			(end -0.12065 0.2794)
			(stroke
				(width 0.1)
				(type default)
			)
			(layer "F.Fab")
		)
		(fp_line
			(start -0.12065 -0.2794)
			(end 0.12065 -0.2794)
			(stroke
				(width 0.1)
				(type default)
			)
			(layer "F.Fab")
		)
		(fp_line
			(start 0.12065 -0.2794)
			(end 0.12065 -0.3048)
			(stroke
				(width 0.1)
				(type default)
			)
			(layer "F.Fab")
		)
		(fp_line
			(start 0.12065 -0.3048)
			(end 0.67945 -0.3048)
			(stroke
				(width 0.1)
				(type default)
			)
			(layer "F.Fab")
		)
		(fp_line
			(start 0.67945 -0.3048)
			(end 0.67945 0.3048)
			(stroke
				(width 0.1)
				(type default)
			)
			(layer "F.Fab")
		)
		(fp_line
			(start -0.67945 -0.305054)
			(end -0.12065 -0.305054)
			(stroke
				(width 0.1)
				(type default)
			)
			(layer "F.Fab")
		)
		(fp_line
			(start -0.12065 -0.305054)
			(end -0.12065 -0.2794)
			(stroke
				(width 0.1)
				(type default)
			)
			(layer "F.Fab")
		)
		(pad "1" smd circle
			(at -0.40005 0 270)
			(size 0 0)
			(layers "F.Cu" "F.Mask" "F.Paste")
			(net "P3V3_AUX")
		)
		(pad "2" smd circle
			(at 0.40005 0 270)
			(size 0 0)
			(layers "F.Cu" "F.Mask" "F.Paste")
			(net "MB_BIC_READY_BUF_N")
		)
	)
	(footprint ""
		(layer "F.Cu")
		(at 63.824612 -158.080202 90)
		(property "Reference" "R2472"
			(at 0 0 90)
			(layer "F.SilkS")
			(hide yes)
			(effects
				(font
					(size 1.27 1.27)
				)
			)
		)
		(property "Value" ""
			(at 0 0 90)
			(layer "F.Fab")
			(effects
				(font
					(size 1.27 1.27)
				)
			)
		)
		(duplicate_pad_numbers_are_jumpers no)
		(fp_line
			(start 0.7874 -0.4064)
			(end 0.7874 0.4064)
			(stroke
				(width 0.1524)
				(type default)
			)
			(layer "F.SilkS")
		)
		(fp_line
			(start -0.7874 -0.4064)
			(end 0.7874 -0.4064)
			(stroke
				(width 0.1524)
				(type default)
			)
			(layer "F.SilkS")
		)
		(fp_line
			(start 0.7874 0.4064)
			(end -0.7874 0.4064)
			(stroke
				(width 0.1524)
				(type default)
			)
			(layer "F.SilkS")
		)
		(fp_line
			(start -0.7874 0.4064)
			(end -0.7874 -0.4064)
			(stroke
				(width 0.1524)
				(type default)
			)
			(layer "F.SilkS")
		)
		(fp_line
			(start -0.12065 -0.305054)
			(end -0.12065 -0.2794)
			(stroke
				(width 0.1)
				(type default)
			)
			(layer "F.Fab")
		)
		(fp_line
			(start -0.67945 -0.305054)
			(end -0.12065 -0.305054)
			(stroke
				(width 0.1)
				(type default)
			)
			(layer "F.Fab")
		)
		(fp_line
			(start 0.67945 -0.3048)
			(end 0.67945 0.3048)
			(stroke
				(width 0.1)
				(type default)
			)
			(layer "F.Fab")
		)
		(fp_line
			(start 0.12065 -0.3048)
			(end 0.67945 -0.3048)
			(stroke
				(width 0.1)
				(type default)
			)
			(layer "F.Fab")
		)
		(fp_line
			(start 0.12065 -0.2794)
			(end 0.12065 -0.3048)
			(stroke
				(width 0.1)
				(type default)
			)
			(layer "F.Fab")
		)
		(fp_line
			(start -0.12065 -0.2794)
			(end 0.12065 -0.2794)
			(stroke
				(width 0.1)
				(type default)
			)
			(layer "F.Fab")
		)
		(fp_line
			(start 0.120396 0.2794)
			(end -0.12065 0.2794)
			(stroke
				(width 0.1)
				(type default)
			)
			(layer "F.Fab")
		)
		(fp_line
			(start -0.12065 0.2794)
			(end -0.12065 0.3048)
			(stroke
				(width 0.1)
				(type default)
			)
			(layer "F.Fab")
		)
		(fp_line
			(start 0.67945 0.3048)
			(end 0.120396 0.3048)
			(stroke
				(width 0.1)
				(type default)
			)
			(layer "F.Fab")
		)
		(fp_line
			(start 0.120396 0.3048)
			(end 0.120396 0.2794)
			(stroke
				(width 0.1)
				(type default)
			)
			(layer "F.Fab")
		)
		(fp_line
			(start -0.12065 0.3048)
			(end -0.67945 0.3048)
			(stroke
				(width 0.1)
				(type default)
			)
			(layer "F.Fab")
		)
		(fp_line
			(start -0.67945 0.3048)
			(end -0.67945 -0.305054)
			(stroke
				(width 0.1)
				(type default)
			)
			(layer "F.Fab")
		)
		(pad "1" smd circle
			(at -0.40005 0 90)
			(size 0 0)
			(layers "F.Cu" "F.Mask" "F.Paste")
			(net "NIC1_PWRBRK_R_N")
		)
		(pad "2" smd circle
			(at 0.40005 0 90)
			(size 0 0)
			(layers "F.Cu" "F.Mask" "F.Paste")
			(net "NIC1_PWRBRK_N")
		)
	)
	(footprint ""
		(layer "F.Cu")
		(at 15.98803 -45.704252 90)
		(property "Reference" "R506"
			(at 0 0 90)
			(layer "F.SilkS")
			(hide yes)
			(effects
				(font
					(size 1.27 1.27)
				)
			)
		)
		(property "Value" ""
			(at 0 0 90)
			(layer "F.Fab")
			(effects
				(font
					(size 1.27 1.27)
				)
			)
		)
		(duplicate_pad_numbers_are_jumpers no)
		(fp_line
			(start 3.937508 -1.8796)
			(end -3.937508 -1.8796)
			(stroke
				(width 0.1524)
				(type default)
			)
			(layer "F.SilkS")
		)
		(fp_line
			(start -3.937508 -1.8796)
			(end -3.937508 1.8796)
			(stroke
				(width 0.1524)
				(type default)
			)
			(layer "F.SilkS")
		)
		(fp_line
			(start 3.937508 1.8796)
			(end 3.937508 -1.8796)
			(stroke
				(width 0.1524)
				(type default)
			)
			(layer "F.SilkS")
		)
		(fp_line
			(start -3.937508 1.8796)
			(end 3.937508 1.8796)
			(stroke
				(width 0.1524)
				(type default)
			)
			(layer "F.SilkS")
		)
		(fp_line
			(start 3.275076 -1.674876)
			(end -3.275076 -1.674876)
			(stroke
				(width 0.1)
				(type default)
			)
			(layer "F.Fab")
		)
		(fp_line
			(start -3.275076 -1.674876)
			(end -3.275076 1.674876)
			(stroke
				(width 0.1)
				(type default)
			)
			(layer "F.Fab")
		)
		(fp_line
			(start 3.275076 1.674876)
			(end 3.275076 -1.674876)
			(stroke
				(width 0.1)
				(type default)
			)
			(layer "F.Fab")
		)
		(fp_line
			(start -3.275076 1.674876)
			(end 3.275076 1.674876)
			(stroke
				(width 0.1)
				(type default)
			)
			(layer "F.Fab")
		)
		(pad "1" smd rect
			(at -2.350008 0 90)
			(size 2.921 3.5052)
			(layers "F.Cu" "F.Mask" "F.Paste")
			(net "P12V_SSD0")
		)
		(pad "2" smd rect
			(at 2.350008 0 90)
			(size 2.921 3.5052)
			(layers "F.Cu" "F.Mask" "F.Paste")
			(net "P12V_SSD0_R")
		)
	)
	(footprint ""
		(layer "F.Cu")
		(at 98.672904 -22.867366 90)
		(property "Reference" "C3893"
			(at 0 0 90)
			(layer "F.SilkS")
			(hide yes)
			(effects
				(font
					(size 1.27 1.27)
				)
			)
		)
		(property "Value" ""
			(at 0 0 90)
			(layer "F.Fab")
			(effects
				(font
					(size 1.27 1.27)
				)
			)
		)
		(duplicate_pad_numbers_are_jumpers no)
		(fp_line
			(start 0.7874 -0.4064)
			(end 0.7874 0.4064)
			(stroke
				(width 0.1524)
				(type default)
			)
			(layer "F.SilkS")
		)
		(fp_line
			(start -0.7874 -0.4064)
			(end 0.7874 -0.4064)
			(stroke
				(width 0.1524)
				(type default)
			)
			(layer "F.SilkS")
		)
		(fp_line
			(start 0.7874 0.4064)
			(end -0.7874 0.4064)
			(stroke
				(width 0.1524)
				(type default)
			)
			(layer "F.SilkS")
		)
		(fp_line
			(start -0.7874 0.4064)
			(end -0.7874 -0.4064)
			(stroke
				(width 0.1524)
				(type default)
			)
			(layer "F.SilkS")
		)
		(fp_line
			(start -0.12065 -0.305054)
			(end -0.12065 -0.2794)
			(stroke
				(width 0.1)
				(type default)
			)
			(layer "F.Fab")
		)
		(fp_line
			(start -0.67945 -0.305054)
			(end -0.12065 -0.305054)
			(stroke
				(width 0.1)
				(type default)
			)
			(layer "F.Fab")
		)
		(fp_line
			(start 0.67945 -0.3048)
			(end 0.67945 0.3048)
			(stroke
				(width 0.1)
				(type default)
			)
			(layer "F.Fab")
		)
		(fp_line
			(start 0.12065 -0.3048)
			(end 0.67945 -0.3048)
			(stroke
				(width 0.1)
				(type default)
			)
			(layer "F.Fab")
		)
		(fp_line
			(start 0.12065 -0.2794)
			(end 0.12065 -0.3048)
			(stroke
				(width 0.1)
				(type default)
			)
			(layer "F.Fab")
		)
		(fp_line
			(start -0.12065 -0.2794)
			(end 0.12065 -0.2794)
			(stroke
				(width 0.1)
				(type default)
			)
			(layer "F.Fab")
		)
		(fp_line
			(start 0.120396 0.2794)
			(end -0.12065 0.2794)
			(stroke
				(width 0.1)
				(type default)
			)
			(layer "F.Fab")
		)
		(fp_line
			(start -0.12065 0.2794)
			(end -0.12065 0.3048)
			(stroke
				(width 0.1)
				(type default)
			)
			(layer "F.Fab")
		)
		(fp_line
			(start 0.67945 0.3048)
			(end 0.120396 0.3048)
			(stroke
				(width 0.1)
				(type default)
			)
			(layer "F.Fab")
		)
		(fp_line
			(start 0.120396 0.3048)
			(end 0.120396 0.2794)
			(stroke
				(width 0.1)
				(type default)
			)
			(layer "F.Fab")
		)
		(fp_line
			(start -0.12065 0.3048)
			(end -0.67945 0.3048)
			(stroke
				(width 0.1)
				(type default)
			)
			(layer "F.Fab")
		)
		(fp_line
			(start -0.67945 0.3048)
			(end -0.67945 -0.305054)
			(stroke
				(width 0.1)
				(type default)
			)
			(layer "F.Fab")
		)
		(pad "1" smd circle
			(at -0.40005 0 90)
			(size 0 0)
			(layers "F.Cu" "F.Mask" "F.Paste")
			(net "P12V_SSD3")
		)
		(pad "2" smd circle
			(at 0.40005 0 90)
			(size 0 0)
			(layers "F.Cu" "F.Mask" "F.Paste")
			(net "GND")
		)
	)
	(footprint ""
		(layer "F.Cu")
		(at 433.615084 -20.72513)
		(property "Reference" "H103"
			(at 1.573022 -2.614168 0)
			(unlocked yes)
			(layer "B.SilkS")
			(effects
				(font
					(size 0.7874 0.5842)
					(thickness 0.1524)
				)
				(justify left mirror)
			)
		)
		(property "Value" ""
			(at 0 0 0)
			(layer "F.Fab")
			(effects
				(font
					(size 1.27 1.27)
				)
			)
		)
		(duplicate_pad_numbers_are_jumpers no)
		(pad "1" thru_hole rect
			(at 0 0)
			(size 4.2164 5.0038)
			(drill 2.0066
				(offset 0.099822 0)
			)
			(layers "*.Cu" "*.Mask")
			(remove_unused_layers no)
			(net "Net_8560")
			(clearance -0.8509)
			(padstack
				(mode front_inner_back)
				(layer "Inner"
					(shape circle)
					(size 4.0132 4.0132)
					(clearance -0.7493)
				)
				(layer "B.Cu"
					(shape circle)
					(size 4.0132 4.0132)
					(clearance -0.7493)
				)
			)
		)
	)
)
